(kicad_pcb
	(version 20260206)
	(generator "pcbnew")
	(generator_version "10.0")
	(general
		(thickness 1.6)
		(legacy_teardrops no)
	)
	(paper "A4")
	(title_block
		(title "v2-pdb — ms_pdb_v2.brd")
		(comment 1 "Open CloudServer (Microsoft) / footprints 312-314 of 348")
	)
	(layers
		(0 "F.Cu" signal "TOP")
		(4 "In1.Cu" signal "GND")
		(6 "In2.Cu" signal "IN1")
		(8 "In3.Cu" signal "VCC")
		(10 "In4.Cu" signal "VCC1")
		(12 "In5.Cu" signal "IN2")
		(14 "In6.Cu" signal "GND1")
		(2 "B.Cu" signal "BOTTOM")
		(9 "F.Adhes" user "F.Adhesive")
		(11 "B.Adhes" user "B.Adhesive")
		(13 "F.Paste" user "Package Geometry/Pastemask Top")
		(15 "B.Paste" user "Package Geometry/Pastemask Bottom")
		(5 "F.SilkS" user "Ref Des/Silkscreen Top")
		(7 "B.SilkS" user "Ref Des/Silkscreen Bottom")
		(1 "F.Mask" user "Board Geometry/Soldermask Top")
		(3 "B.Mask" user "Board Geometry/Soldermask Bottom")
		(17 "Dwgs.User" user "User.Drawings")
		(19 "Cmts.User" user "User.Comments")
		(21 "Eco1.User" user "User.Eco1")
		(23 "Eco2.User" user "User.Eco2")
		(25 "Edge.Cuts" user "Board Geometry/Outline")
		(27 "Margin" user)
		(31 "F.CrtYd" user "Package Geometry/Place Bound Top")
		(29 "B.CrtYd" user "Package Geometry/Place Bound Bottom")
		(35 "F.Fab" user "Ref Des/Assembly Top")
		(33 "B.Fab" user "Ref Des/Assembly Bottom")
	)
	(footprint ""
		(layer "F.Cu")
		(at 16.599916 -473.69984)
		(property "Reference" "H8"
			(at -6.4516 -7.127748 0)
			(unlocked yes)
			(layer "F.SilkS")
			(effects
				(font
					(size 0.7874 0.5842)
					(thickness 0.1524)
				)
				(justify left)
			)
		)
		(property "Value" ""
			(at 0 0 0)
			(layer "F.Fab")
			(effects
				(font
					(size 1.27 1.27)
				)
			)
		)
		(duplicate_pad_numbers_are_jumpers no)
		(fp_circle
			(center 0 0)
			(end 7.999984 0)
			(stroke
				(width 0.1524)
				(type default)
			)
			(fill no)
			(layer "F.SilkS")
		)
		(fp_circle
			(center 0 0)
			(end 14.7066 0)
			(stroke
				(width 0.1524)
				(type default)
			)
			(fill no)
			(layer "B.SilkS")
		)
		(fp_poly
			(pts
				(arc
					(start 0 5.0038)
					(mid 0 -5.0038)
					(end 0 5.0038)
				)
			)
			(stroke
				(width 0)
				(type default)
			)
			(fill no)
			(layer "F.CrtYd")
		)
		(pad "" np_thru_hole circle
			(at 0 0)
			(size 4.0132 4.0132)
			(drill 4.0132)
			(layers "*.Cu" "*.Mask")
			(clearance 0.381)
			(thermal_gap 0.381)
		)
		(pad "2" thru_hole circle
			(at 0 -3.50012)
			(size 0.762 0.762)
			(drill 0.5588)
			(layers "*.Cu" "*.Mask")
			(remove_unused_layers no)
			(net "GND")
			(clearance 0.1524)
			(thermal_gap 0.1524)
		)
		(pad "3" thru_hole circle
			(at -2.500122 -2.500122)
			(size 0.762 0.762)
			(drill 0.5588)
			(layers "*.Cu" "*.Mask")
			(remove_unused_layers no)
			(net "GND")
			(clearance 0.1524)
			(thermal_gap 0.1524)
		)
		(pad "4" thru_hole circle
			(at -3.50012 0)
			(size 0.762 0.762)
			(drill 0.5588)
			(layers "*.Cu" "*.Mask")
			(remove_unused_layers no)
			(net "GND")
			(clearance 0.1524)
			(thermal_gap 0.1524)
		)
		(pad "5" thru_hole circle
			(at -2.500122 2.500122)
			(size 0.762 0.762)
			(drill 0.5588)
			(layers "*.Cu" "*.Mask")
			(remove_unused_layers no)
			(net "GND")
			(clearance 0.1524)
			(thermal_gap 0.1524)
		)
		(pad "6" thru_hole circle
			(at 0 3.50012)
			(size 0.762 0.762)
			(drill 0.5588)
			(layers "*.Cu" "*.Mask")
			(remove_unused_layers no)
			(net "GND")
			(clearance 0.1524)
			(thermal_gap 0.1524)
		)
		(pad "7" thru_hole circle
			(at 2.500122 2.500122)
			(size 0.762 0.762)
			(drill 0.5588)
			(layers "*.Cu" "*.Mask")
			(remove_unused_layers no)
			(net "GND")
			(clearance 0.1524)
			(thermal_gap 0.1524)
		)
		(pad "8" thru_hole circle
			(at 3.50012 0)
			(size 0.762 0.762)
			(drill 0.5588)
			(layers "*.Cu" "*.Mask")
			(remove_unused_layers no)
			(net "GND")
			(clearance 0.1524)
			(thermal_gap 0.1524)
		)
		(pad "9" thru_hole circle
			(at 2.500122 -2.500122)
			(size 0.762 0.762)
			(drill 0.5588)
			(layers "*.Cu" "*.Mask")
			(remove_unused_layers no)
			(net "GND")
			(clearance 0.1524)
			(thermal_gap 0.1524)
		)
		(zone
			(layer "F.Cu")
			(hatch none 0.5)
			(connect_pads
				(clearance 0)
			)
			(min_thickness 0.25)
			(keepout
				(tracks not_allowed)
				(vias allowed)
				(pads allowed)
				(copperpour not_allowed)
				(footprints allowed)
			)
			(placement
				(enabled no)
				(sheetname "")
			)
			(fill
				(thermal_gap 0.5)
				(thermal_bridge_width 0.5)
				(island_removal_mode 0)
			)
			(polygon
				(pts
					(arc
						(start 16.599916 -481.70084)
						(mid 8.598916 -473.69984)
						(end 16.599916 -465.69884)
					)
					(arc
						(start 16.599916 -465.69884)
						(mid 18.035016 -467.13394)
						(end 16.599916 -468.56904)
					)
					(arc
						(start 16.599916 -468.56904)
						(mid 11.469116 -473.69984)
						(end 16.599916 -478.83064)
					)
					(arc
						(start 16.599916 -478.83064)
						(mid 18.035016 -480.26574)
						(end 16.599916 -481.70084)
					)
				)
			)
		)
		(zone
			(layer "F.Cu")
			(hatch none 0.5)
			(connect_pads
				(clearance 0)
			)
			(min_thickness 0.25)
			(keepout
				(tracks not_allowed)
				(vias allowed)
				(pads allowed)
				(copperpour not_allowed)
				(footprints allowed)
			)
			(placement
				(enabled no)
				(sheetname "")
			)
			(fill
				(thermal_gap 0.5)
				(thermal_bridge_width 0.5)
				(island_removal_mode 0)
			)
			(polygon
				(pts
					(arc
						(start 16.599916 -481.70084)
						(mid 24.600916 -473.69984)
						(end 16.599916 -465.69884)
					)
					(arc
						(start 16.599916 -465.69884)
						(mid 15.164816 -467.13394)
						(end 16.599916 -468.56904)
					)
					(arc
						(start 16.599916 -468.56904)
						(mid 21.730716 -473.69984)
						(end 16.599916 -478.83064)
					)
					(arc
						(start 16.599916 -478.83064)
						(mid 15.164816 -480.26574)
						(end 16.599916 -481.70084)
					)
				)
			)
		)
		(zone
			(layers "F.Cu" "B.Cu" "In1.Cu" "In2.Cu" "In3.Cu" "In4.Cu" "In5.Cu" "In6.Cu")
			(hatch none 0.5)
			(connect_pads
				(clearance 0)
			)
			(min_thickness 0.25)
			(keepout
				(tracks not_allowed)
				(vias allowed)
				(pads allowed)
				(copperpour not_allowed)
				(footprints allowed)
			)
			(placement
				(enabled no)
				(sheetname "")
			)
			(fill
				(thermal_gap 0.5)
				(thermal_bridge_width 0.5)
				(island_removal_mode 0)
			)
			(polygon
				(pts
					(arc
						(start 16.599916 -471.18778)
						(mid 16.599916 -476.2119)
						(end 16.599916 -471.18778)
					)
				)
			)
		)
	)
	(footprint ""
		(layer "F.Cu")
		(at 77.999844 -430.150016)
		(property "Reference" "H3"
			(at -7.733284 -6.395466 0)
			(unlocked yes)
			(layer "F.SilkS")
			(effects
				(font
					(size 0.7874 0.5842)
					(thickness 0.1524)
				)
				(justify left)
			)
		)
		(property "Value" ""
			(at 0 0 0)
			(layer "F.Fab")
			(effects
				(font
					(size 1.27 1.27)
				)
			)
		)
		(duplicate_pad_numbers_are_jumpers no)
		(fp_circle
			(center 0 0)
			(end 7.999984 0)
			(stroke
				(width 0.1524)
				(type default)
			)
			(fill no)
			(layer "F.SilkS")
		)
		(fp_arc
			(start -4.620006 -13.962126)
			(mid 8.612183 -11.921174)
			(end 14.7066 0)
			(stroke
				(width 0.1524)
				(type default)
			)
			(layer "B.SilkS")
		)
		(fp_arc
			(start 14.7066 0)
			(mid -8.042606 12.311424)
			(end -5.908802 -13.467334)
			(stroke
				(width 0.1524)
				(type default)
			)
			(layer "B.SilkS")
		)
		(fp_poly
			(pts
				(arc
					(start 5.0038 0)
					(mid -5.0038 0)
					(end 5.0038 0)
				)
			)
			(stroke
				(width 0)
				(type default)
			)
			(fill no)
			(layer "F.CrtYd")
		)
		(pad "" np_thru_hole circle
			(at 0 0)
			(size 4.0132 4.0132)
			(drill 4.0132)
			(layers "*.Cu" "*.Mask")
			(clearance 0.381)
			(thermal_gap 0.381)
		)
		(pad "2" thru_hole circle
			(at 0 -3.50012)
			(size 0.762 0.762)
			(drill 0.5588)
			(layers "*.Cu" "*.Mask")
			(remove_unused_layers no)
			(net "GND")
			(clearance 0.1524)
			(thermal_gap 0.1524)
		)
		(pad "3" thru_hole circle
			(at -2.500122 -2.500122)
			(size 0.762 0.762)
			(drill 0.5588)
			(layers "*.Cu" "*.Mask")
			(remove_unused_layers no)
			(net "GND")
			(clearance 0.1524)
			(thermal_gap 0.1524)
		)
		(pad "4" thru_hole circle
			(at -3.50012 0)
			(size 0.762 0.762)
			(drill 0.5588)
			(layers "*.Cu" "*.Mask")
			(remove_unused_layers no)
			(net "GND")
			(clearance 0.1524)
			(thermal_gap 0.1524)
		)
		(pad "5" thru_hole circle
			(at -2.500122 2.500122)
			(size 0.762 0.762)
			(drill 0.5588)
			(layers "*.Cu" "*.Mask")
			(remove_unused_layers no)
			(net "GND")
			(clearance 0.1524)
			(thermal_gap 0.1524)
		)
		(pad "6" thru_hole circle
			(at 0 3.50012)
			(size 0.762 0.762)
			(drill 0.5588)
			(layers "*.Cu" "*.Mask")
			(remove_unused_layers no)
			(net "GND")
			(clearance 0.1524)
			(thermal_gap 0.1524)
		)
		(pad "7" thru_hole circle
			(at 2.500122 2.500122)
			(size 0.762 0.762)
			(drill 0.5588)
			(layers "*.Cu" "*.Mask")
			(remove_unused_layers no)
			(net "GND")
			(clearance 0.1524)
			(thermal_gap 0.1524)
		)
		(pad "8" thru_hole circle
			(at 3.50012 0)
			(size 0.762 0.762)
			(drill 0.5588)
			(layers "*.Cu" "*.Mask")
			(remove_unused_layers no)
			(net "GND")
			(clearance 0.1524)
			(thermal_gap 0.1524)
		)
		(pad "9" thru_hole circle
			(at 2.500122 -2.500122)
			(size 0.762 0.762)
			(drill 0.5588)
			(layers "*.Cu" "*.Mask")
			(remove_unused_layers no)
			(net "GND")
			(clearance 0.1524)
			(thermal_gap 0.1524)
		)
		(zone
			(layer "F.Cu")
			(hatch none 0.5)
			(connect_pads
				(clearance 0)
			)
			(min_thickness 0.25)
			(keepout
				(tracks not_allowed)
				(vias allowed)
				(pads allowed)
				(copperpour not_allowed)
				(footprints allowed)
			)
			(placement
				(enabled no)
				(sheetname "")
			)
			(fill
				(thermal_gap 0.5)
				(thermal_bridge_width 0.5)
				(island_removal_mode 0)
			)
			(polygon
				(pts
					(arc
						(start 77.999844 -438.151016)
						(mid 69.998844 -430.150016)
						(end 77.999844 -422.149016)
					)
					(arc
						(start 77.999844 -422.149016)
						(mid 79.434944 -423.584116)
						(end 77.999844 -425.019216)
					)
					(arc
						(start 77.999844 -425.019216)
						(mid 72.869044 -430.150016)
						(end 77.999844 -435.280816)
					)
					(arc
						(start 77.999844 -435.280816)
						(mid 79.434944 -436.715916)
						(end 77.999844 -438.151016)
					)
				)
			)
		)
		(zone
			(layer "F.Cu")
			(hatch none 0.5)
			(connect_pads
				(clearance 0)
			)
			(min_thickness 0.25)
			(keepout
				(tracks not_allowed)
				(vias allowed)
				(pads allowed)
				(copperpour not_allowed)
				(footprints allowed)
			)
			(placement
				(enabled no)
				(sheetname "")
			)
			(fill
				(thermal_gap 0.5)
				(thermal_bridge_width 0.5)
				(island_removal_mode 0)
			)
			(polygon
				(pts
					(arc
						(start 77.999844 -438.151016)
						(mid 86.000844 -430.150016)
						(end 77.999844 -422.149016)
					)
					(arc
						(start 77.999844 -422.149016)
						(mid 76.564744 -423.584116)
						(end 77.999844 -425.019216)
					)
					(arc
						(start 77.999844 -425.019216)
						(mid 83.130644 -430.150016)
						(end 77.999844 -435.280816)
					)
					(arc
						(start 77.999844 -435.280816)
						(mid 76.564744 -436.715916)
						(end 77.999844 -438.151016)
					)
				)
			)
		)
		(zone
			(layers "F.Cu" "B.Cu" "In1.Cu" "In2.Cu" "In3.Cu" "In4.Cu" "In5.Cu" "In6.Cu")
			(hatch none 0.5)
			(connect_pads
				(clearance 0)
			)
			(min_thickness 0.25)
			(keepout
				(tracks not_allowed)
				(vias allowed)
				(pads allowed)
				(copperpour not_allowed)
				(footprints allowed)
			)
			(placement
				(enabled no)
				(sheetname "")
			)
			(fill
				(thermal_gap 0.5)
				(thermal_bridge_width 0.5)
				(island_removal_mode 0)
			)
			(polygon
				(pts
					(arc
						(start 80.511904 -430.150016)
						(mid 75.487784 -430.150016)
						(end 80.511904 -430.150016)
					)
				)
			)
		)
	)
	(footprint ""
		(layer "F.Cu")
		(at 5.780024 -517.049766)
		(property "Reference" "J32"
			(at -1.9304 -3.978148 0)
			(unlocked yes)
			(layer "F.SilkS")
			(effects
				(font
					(size 0.7874 0.5842)
					(thickness 0.1524)
				)
				(justify left)
			)
		)
		(property "Value" ""
			(at 0 0 0)
			(layer "F.Fab")
			(effects
				(font
					(size 1.27 1.27)
				)
			)
		)
		(duplicate_pad_numbers_are_jumpers no)
		(fp_line
			(start -3.10007 0.199898)
			(end -3.10007 2.800096)
			(stroke
				(width 0.1524)
				(type default)
			)
			(layer "F.SilkS")
		)
		(fp_line
			(start -3.10007 2.800096)
			(end -1.89992 2.800096)
			(stroke
				(width 0.1524)
				(type default)
			)
			(layer "F.SilkS")
		)
		(fp_line
			(start -1.89992 -3.325114)
			(end -1.89992 0.199898)
			(stroke
				(width 0.1524)
				(type default)
			)
			(layer "F.SilkS")
		)
		(fp_line
			(start -1.89992 0.199898)
			(end -3.10007 0.199898)
			(stroke
				(width 0.1524)
				(type default)
			)
			(layer "F.SilkS")
		)
		(fp_line
			(start -1.89992 2.800096)
			(end -1.89992 6.325108)
			(stroke
				(width 0.1524)
				(type default)
			)
			(layer "F.SilkS")
		)
		(fp_line
			(start -1.89992 6.325108)
			(end 1.016 6.325108)
			(stroke
				(width 0.1524)
				(type default)
			)
			(layer "F.SilkS")
		)
		(fp_line
			(start 1.016 -3.325114)
			(end -1.89992 -3.325114)
			(stroke
				(width 0.1524)
				(type default)
			)
			(layer "F.SilkS")
		)
		(fp_line
			(start 2.469896 5.133594)
			(end 2.469896 -2.130806)
			(stroke
				(width 0.1524)
				(type default)
			)
			(layer "F.SilkS")
		)
		(fp_poly
			(pts
				(xy 0.8509 0.8509) (xy -0.8509 0.8509) (xy -0.8509 -0.8509) (xy 0.8509 -0.8509)
			)
			(stroke
				(width 0)
				(type default)
			)
			(fill no)
			(layer "B.CrtYd")
		)
		(fp_poly
			(pts
				(arc
					(start 0.8509 2.999994)
					(mid -0.8509 2.999994)
					(end 0.8509 2.999994)
				)
			)
			(stroke
				(width 0)
				(type default)
			)
			(fill no)
			(layer "B.CrtYd")
		)
		(fp_poly
			(pts
				(arc
					(start 2.874518 -2.999994)
					(mid 1.045718 -2.999994)
					(end 2.874518 -2.999994)
				)
			)
			(stroke
				(width 0)
				(type default)
			)
			(fill no)
			(layer "B.CrtYd")
		)
		(fp_poly
			(pts
				(arc
					(start 2.874518 5.999988)
					(mid 1.045718 5.999988)
					(end 2.874518 5.999988)
				)
			)
			(stroke
				(width 0)
				(type default)
			)
			(fill no)
			(layer "B.CrtYd")
		)
		(fp_poly
			(pts
				(xy 2.469896 5.233924) (xy 2.469896 -2.233676) (xy 2.8956 -2.233676) (xy 2.8956 -3.935476) (xy 1.0922 -3.935476)
				(xy 1.0922 -3.325114) (xy -1.89992 -3.325114) (xy -1.89992 0.199898) (xy -3.10007 0.199898) (xy -3.10007 2.800096)
				(xy -1.89992 2.800096) (xy -1.89992 6.325108) (xy 1.0922 6.325108) (xy 1.0922 6.935724) (xy 2.8956 6.935724)
				(xy 2.8956 5.233924)
			)
			(stroke
				(width 0)
				(type default)
			)
			(fill no)
			(layer "F.CrtYd")
		)
		(fp_line
			(start -3.10007 0.199898)
			(end -3.10007 2.800096)
			(stroke
				(width 0.1)
				(type default)
			)
			(layer "F.Fab")
		)
		(fp_line
			(start -3.10007 2.800096)
			(end -1.89992 2.800096)
			(stroke
				(width 0.1)
				(type default)
			)
			(layer "F.Fab")
		)
		(fp_line
			(start -1.89992 -3.325114)
			(end -1.89992 0.199898)
			(stroke
				(width 0.1)
				(type default)
			)
			(layer "F.Fab")
		)
		(fp_line
			(start -1.89992 0.199898)
			(end -3.10007 0.199898)
			(stroke
				(width 0.1)
				(type default)
			)
			(layer "F.Fab")
		)
		(fp_line
			(start -1.89992 2.800096)
			(end -1.89992 6.325108)
			(stroke
				(width 0.1)
				(type default)
			)
			(layer "F.Fab")
		)
		(fp_line
			(start -1.89992 6.325108)
			(end 2.469896 6.325108)
			(stroke
				(width 0.1)
				(type default)
			)
			(layer "F.Fab")
		)
		(fp_line
			(start 2.469896 -3.325114)
			(end -1.89992 -3.325114)
			(stroke
				(width 0.1)
				(type default)
			)
			(layer "F.Fab")
		)
		(fp_line
			(start 2.469896 6.325108)
			(end 2.469896 -3.325114)
			(stroke
				(width 0.1)
				(type default)
			)
			(layer "F.Fab")
		)
		(pad "" np_thru_hole circle
			(at 1.960118 -2.999994 90)
			(size 1.3208 1.3208)
			(drill 1.3208)
			(layers "*.Cu" "*.Mask")
			(clearance 0.381)
			(thermal_gap 0.381)
		)
		(pad "" np_thru_hole circle
			(at 1.960118 5.999988 90)
			(size 1.3208 1.3208)
			(drill 1.3208)
			(layers "*.Cu" "*.Mask")
			(clearance 0.381)
			(thermal_gap 0.381)
		)
		(pad "1" thru_hole rect
			(at 0 0 90)
			(size 1.6002 1.6002)
			(drill 1.0922)
			(layers "*.Cu" "*.Mask")
			(remove_unused_layers no)
			(net "POWER_SW1_PWR_CTR_12V")
			(clearance 0)
			(padstack
				(mode front_inner_back)
				(layer "Inner"
					(shape circle)
					(size 1.6002 1.6002)
					(clearance 0)
				)
				(layer "B.Cu"
					(shape rect)
					(size 1.6002 1.6002)
					(clearance 0)
				)
			)
		)
		(pad "2" thru_hole circle
			(at 0 2.999994 90)
			(size 1.6002 1.6002)
			(drill 1.0922)
			(layers "*.Cu" "*.Mask")
			(remove_unused_layers no)
			(net "GND")
			(clearance 0)
		)
		(zone
			(layers "F.Cu" "B.Cu" "In1.Cu" "In2.Cu" "In3.Cu" "In4.Cu" "In5.Cu" "In6.Cu")
			(hatch none 0.5)
			(connect_pads
				(clearance 0)
			)
			(min_thickness 0.25)
			(keepout
				(tracks not_allowed)
				(vias allowed)
				(pads allowed)
				(copperpour not_allowed)
				(footprints allowed)
			)
			(placement
				(enabled no)
				(sheetname "")
			)
			(fill
				(thermal_gap 0.5)
				(thermal_bridge_width 0.5)
				(island_removal_mode 0)
			)
			(polygon
				(pts
					(arc
						(start 8.806942 -520.04976)
						(mid 6.673342 -520.04976)
						(end 8.806942 -520.04976)
					)
				)
			)
		)
		(zone
			(layers "F.Cu" "B.Cu" "In1.Cu" "In2.Cu" "In3.Cu" "In4.Cu" "In5.Cu" "In6.Cu")
			(hatch none 0.5)
			(connect_pads
				(clearance 0)
			)
			(min_thickness 0.25)
			(keepout
				(tracks not_allowed)
				(vias allowed)
				(pads allowed)
				(copperpour not_allowed)
				(footprints allowed)
			)
			(placement
				(enabled no)
				(sheetname "")
			)
			(fill
				(thermal_gap 0.5)
				(thermal_bridge_width 0.5)
				(island_removal_mode 0)
			)
			(polygon
				(pts
					(arc
						(start 8.806942 -511.049778)
						(mid 6.673342 -511.049778)
						(end 8.806942 -511.049778)
					)
				)
			)
		)
	)
)
